(kicad_pcb
	(version 20260206)
	(generator "pcbnew")
	(generator_version "10.0")
	(general
		(thickness 1.6)
		(legacy_teardrops no)
	)
	(paper "A4")
	(title_block
		(title "03242023_DA0F0TMBIJ0_F0T_Motherboard_J_brd_V01_OCP.brd")
		(comment 1 "Grand Teton / footprints 1412-1417 of 6105")
	)
	(layers
		(0 "F.Cu" signal "TOP")
		(4 "In1.Cu" signal "GND")
		(6 "In2.Cu" signal "IN1")
		(8 "In3.Cu" signal "GND1")
		(10 "In4.Cu" signal "IN2")
		(12 "In5.Cu" signal "GND2")
		(14 "In6.Cu" signal "IN3")
		(16 "In7.Cu" signal "GND3")
		(18 "In8.Cu" signal "VCC")
		(20 "In9.Cu" signal "VCC1")
		(22 "In10.Cu" signal "GND4")
		(24 "In11.Cu" signal "IN4")
		(26 "In12.Cu" signal "GND5")
		(28 "In13.Cu" signal "IN5")
		(30 "In14.Cu" signal "GND6")
		(32 "In15.Cu" signal "IN6")
		(34 "In16.Cu" signal "GND7")
		(2 "B.Cu" signal "BOTTOM")
		(9 "F.Adhes" user "F.Adhesive")
		(11 "B.Adhes" user "B.Adhesive")
		(13 "F.Paste" user "Package Geometry/Pastemask Top")
		(15 "B.Paste" user "Package Geometry/Pastemask Bottom")
		(5 "F.SilkS" user "Ref Des/Silkscreen Top")
		(7 "B.SilkS" user "Ref Des/Silkscreen Bottom")
		(1 "F.Mask" user "Board Geometry/Soldermask Top")
		(3 "B.Mask" user "Board Geometry/Soldermask Bottom")
		(17 "Dwgs.User" user "User.Drawings")
		(19 "Cmts.User" user "User.Comments")
		(21 "Eco1.User" user "User.Eco1")
		(23 "Eco2.User" user "User.Eco2")
		(25 "Edge.Cuts" user "Board Geometry/Outline")
		(27 "Margin" user)
		(31 "F.CrtYd" user "Package Geometry/Place Bound Top")
		(29 "B.CrtYd" user "Package Geometry/Place Bound Bottom")
		(35 "F.Fab" user "Ref Des/Assembly Top")
		(33 "B.Fab" user "Ref Des/Assembly Bottom")
	)
	(footprint ""
		(layer "F.Cu")
		(at 114.81308 -393.048998 180)
		(property "Reference" "R3034"
			(at 0 0 180)
			(layer "F.SilkS")
			(hide yes)
			(effects
				(font
					(size 1.27 1.27)
				)
			)
		)
		(property "Value" ""
			(at 0 0 180)
			(layer "F.Fab")
			(effects
				(font
					(size 1.27 1.27)
				)
			)
		)
		(duplicate_pad_numbers_are_jumpers no)
		(fp_line
			(start 0.7874 0.4064)
			(end -0.7874 0.4064)
			(stroke
				(width 0.1524)
				(type default)
			)
			(layer "F.SilkS")
		)
		(fp_line
			(start 0.7874 -0.4064)
			(end 0.7874 0.4064)
			(stroke
				(width 0.1524)
				(type default)
			)
			(layer "F.SilkS")
		)
		(fp_line
			(start -0.7874 0.4064)
			(end -0.7874 -0.4064)
			(stroke
				(width 0.1524)
				(type default)
			)
			(layer "F.SilkS")
		)
		(fp_line
			(start -0.7874 -0.4064)
			(end 0.7874 -0.4064)
			(stroke
				(width 0.1524)
				(type default)
			)
			(layer "F.SilkS")
		)
		(fp_line
			(start 0.67945 0.3048)
			(end 0.120396 0.3048)
			(stroke
				(width 0.1)
				(type default)
			)
			(layer "F.Fab")
		)
		(fp_line
			(start 0.67945 -0.3048)
			(end 0.67945 0.3048)
			(stroke
				(width 0.1)
				(type default)
			)
			(layer "F.Fab")
		)
		(fp_line
			(start 0.12065 -0.2794)
			(end 0.12065 -0.3048)
			(stroke
				(width 0.1)
				(type default)
			)
			(layer "F.Fab")
		)
		(fp_line
			(start 0.12065 -0.3048)
			(end 0.67945 -0.3048)
			(stroke
				(width 0.1)
				(type default)
			)
			(layer "F.Fab")
		)
		(fp_line
			(start 0.120396 0.3048)
			(end 0.120396 0.2794)
			(stroke
				(width 0.1)
				(type default)
			)
			(layer "F.Fab")
		)
		(fp_line
			(start 0.120396 0.2794)
			(end -0.12065 0.2794)
			(stroke
				(width 0.1)
				(type default)
			)
			(layer "F.Fab")
		)
		(fp_line
			(start -0.12065 0.3048)
			(end -0.67945 0.3048)
			(stroke
				(width 0.1)
				(type default)
			)
			(layer "F.Fab")
		)
		(fp_line
			(start -0.12065 0.2794)
			(end -0.12065 0.3048)
			(stroke
				(width 0.1)
				(type default)
			)
			(layer "F.Fab")
		)
		(fp_line
			(start -0.12065 -0.2794)
			(end 0.12065 -0.2794)
			(stroke
				(width 0.1)
				(type default)
			)
			(layer "F.Fab")
		)
		(fp_line
			(start -0.12065 -0.305054)
			(end -0.12065 -0.2794)
			(stroke
				(width 0.1)
				(type default)
			)
			(layer "F.Fab")
		)
		(fp_line
			(start -0.67945 0.3048)
			(end -0.67945 -0.305054)
			(stroke
				(width 0.1)
				(type default)
			)
			(layer "F.Fab")
		)
		(fp_line
			(start -0.67945 -0.305054)
			(end -0.12065 -0.305054)
			(stroke
				(width 0.1)
				(type default)
			)
			(layer "F.Fab")
		)
		(pad "1" smd circle
			(at -0.40005 0 180)
			(size 0 0)
			(layers "F.Cu" "F.Mask" "F.Paste")
			(net "P3V3_AUX")
		)
		(pad "2" smd circle
			(at 0.40005 0 180)
			(size 0 0)
			(layers "F.Cu" "F.Mask" "F.Paste")
			(net "FM_SMB_2_ALERT_GPU")
		)
	)
	(footprint ""
		(layer "F.Cu")
		(at 170.965622 -337.477608)
		(property "Reference" "PC1203"
			(at 0 0 0)
			(layer "F.SilkS")
			(hide yes)
			(effects
				(font
					(size 1.27 1.27)
				)
			)
		)
		(property "Value" ""
			(at 0 0 0)
			(layer "F.Fab")
			(effects
				(font
					(size 1.27 1.27)
				)
			)
		)
		(duplicate_pad_numbers_are_jumpers no)
		(fp_line
			(start 2.750058 0.999998)
			(end -2.750058 0.999998)
			(stroke
				(width 0.1524)
				(type default)
			)
			(layer "F.SilkS")
		)
		(fp_circle
			(center 0 0.999998)
			(end 2.750058 0.999998)
			(stroke
				(width 0.1524)
				(type default)
			)
			(fill no)
			(layer "F.SilkS")
		)
		(fp_poly
			(pts
				(arc
					(start 2.750058 0.999998)
					(mid 0 3.750056)
					(end -2.750058 0.999998)
				)
			)
			(stroke
				(width 0)
				(type default)
			)
			(fill yes)
			(layer "F.SilkS")
		)
		(fp_circle
			(center 0 0.999998)
			(end 2.750058 0.999998)
			(stroke
				(width 0.1)
				(type default)
			)
			(fill no)
			(layer "F.Fab")
		)
		(pad "1" thru_hole rect
			(at 0 0)
			(size 1.5748 1.5748)
			(drill 1.0668)
			(layers "*.Cu" "*.Mask")
			(remove_unused_layers no)
			(net "PVCCFA_EHV_FIVRA_CPU1")
			(clearance 0)
			(padstack
				(mode front_inner_back)
				(layer "Inner"
					(shape circle)
					(size 1.5748 1.5748)
					(clearance 0)
				)
				(layer "B.Cu"
					(shape rect)
					(size 1.5748 1.5748)
					(clearance 0)
				)
			)
		)
		(pad "2" thru_hole circle
			(at 0 1.999996)
			(size 1.5748 1.5748)
			(drill 1.0668)
			(layers "*.Cu" "*.Mask")
			(remove_unused_layers no)
			(net "GND")
			(clearance 0)
		)
	)
	(footprint ""
		(layer "F.Cu")
		(at 428.912782 -107.872276 180)
		(property "Reference" "PR3790"
			(at 0 0 180)
			(layer "F.SilkS")
			(hide yes)
			(effects
				(font
					(size 1.27 1.27)
				)
			)
		)
		(property "Value" ""
			(at 0 0 180)
			(layer "F.Fab")
			(effects
				(font
					(size 1.27 1.27)
				)
			)
		)
		(duplicate_pad_numbers_are_jumpers no)
		(fp_line
			(start 0.7874 0.4064)
			(end -0.7874 0.4064)
			(stroke
				(width 0.1524)
				(type default)
			)
			(layer "F.SilkS")
		)
		(fp_line
			(start 0.7874 -0.4064)
			(end 0.7874 0.4064)
			(stroke
				(width 0.1524)
				(type default)
			)
			(layer "F.SilkS")
		)
		(fp_line
			(start -0.7874 0.4064)
			(end -0.7874 -0.4064)
			(stroke
				(width 0.1524)
				(type default)
			)
			(layer "F.SilkS")
		)
		(fp_line
			(start -0.7874 -0.4064)
			(end 0.7874 -0.4064)
			(stroke
				(width 0.1524)
				(type default)
			)
			(layer "F.SilkS")
		)
		(fp_line
			(start 0.67945 0.3048)
			(end 0.120396 0.3048)
			(stroke
				(width 0.1)
				(type default)
			)
			(layer "F.Fab")
		)
		(fp_line
			(start 0.67945 -0.3048)
			(end 0.67945 0.3048)
			(stroke
				(width 0.1)
				(type default)
			)
			(layer "F.Fab")
		)
		(fp_line
			(start 0.12065 -0.2794)
			(end 0.12065 -0.3048)
			(stroke
				(width 0.1)
				(type default)
			)
			(layer "F.Fab")
		)
		(fp_line
			(start 0.12065 -0.3048)
			(end 0.67945 -0.3048)
			(stroke
				(width 0.1)
				(type default)
			)
			(layer "F.Fab")
		)
		(fp_line
			(start 0.120396 0.3048)
			(end 0.120396 0.2794)
			(stroke
				(width 0.1)
				(type default)
			)
			(layer "F.Fab")
		)
		(fp_line
			(start 0.120396 0.2794)
			(end -0.12065 0.2794)
			(stroke
				(width 0.1)
				(type default)
			)
			(layer "F.Fab")
		)
		(fp_line
			(start -0.12065 0.3048)
			(end -0.67945 0.3048)
			(stroke
				(width 0.1)
				(type default)
			)
			(layer "F.Fab")
		)
		(fp_line
			(start -0.12065 0.2794)
			(end -0.12065 0.3048)
			(stroke
				(width 0.1)
				(type default)
			)
			(layer "F.Fab")
		)
		(fp_line
			(start -0.12065 -0.2794)
			(end 0.12065 -0.2794)
			(stroke
				(width 0.1)
				(type default)
			)
			(layer "F.Fab")
		)
		(fp_line
			(start -0.12065 -0.305054)
			(end -0.12065 -0.2794)
			(stroke
				(width 0.1)
				(type default)
			)
			(layer "F.Fab")
		)
		(fp_line
			(start -0.67945 0.3048)
			(end -0.67945 -0.305054)
			(stroke
				(width 0.1)
				(type default)
			)
			(layer "F.Fab")
		)
		(fp_line
			(start -0.67945 -0.305054)
			(end -0.12065 -0.305054)
			(stroke
				(width 0.1)
				(type default)
			)
			(layer "F.Fab")
		)
		(pad "1" smd circle
			(at -0.40005 0 180)
			(size 0 0)
			(layers "F.Cu" "F.Mask" "F.Paste")
			(net "P3V3_OCP_UV_1")
		)
		(pad "2" smd circle
			(at 0.40005 0 180)
			(size 0 0)
			(layers "F.Cu" "F.Mask" "F.Paste")
			(net "P3V3_OCP_OV_1")
		)
	)
	(footprint ""
		(layer "F.Cu")
		(at 461.720946 -103.614728)
		(property "Reference" "C593"
			(at 0 0 0)
			(layer "F.SilkS")
			(hide yes)
			(effects
				(font
					(size 1.27 1.27)
				)
			)
		)
		(property "Value" ""
			(at 0 0 0)
			(layer "F.Fab")
			(effects
				(font
					(size 1.27 1.27)
				)
			)
		)
		(duplicate_pad_numbers_are_jumpers no)
		(fp_line
			(start -0.7874 -0.4064)
			(end 0.7874 -0.4064)
			(stroke
				(width 0.1524)
				(type default)
			)
			(layer "F.SilkS")
		)
		(fp_line
			(start -0.7874 0.4064)
			(end -0.7874 -0.4064)
			(stroke
				(width 0.1524)
				(type default)
			)
			(layer "F.SilkS")
		)
		(fp_line
			(start 0.7874 -0.4064)
			(end 0.7874 0.4064)
			(stroke
				(width 0.1524)
				(type default)
			)
			(layer "F.SilkS")
		)
		(fp_line
			(start 0.7874 0.4064)
			(end -0.7874 0.4064)
			(stroke
				(width 0.1524)
				(type default)
			)
			(layer "F.SilkS")
		)
		(fp_line
			(start -0.67945 -0.305054)
			(end -0.12065 -0.305054)
			(stroke
				(width 0.1)
				(type default)
			)
			(layer "F.Fab")
		)
		(fp_line
			(start -0.67945 0.3048)
			(end -0.67945 -0.305054)
			(stroke
				(width 0.1)
				(type default)
			)
			(layer "F.Fab")
		)
		(fp_line
			(start -0.12065 -0.305054)
			(end -0.12065 -0.2794)
			(stroke
				(width 0.1)
				(type default)
			)
			(layer "F.Fab")
		)
		(fp_line
			(start -0.12065 -0.2794)
			(end 0.12065 -0.2794)
			(stroke
				(width 0.1)
				(type default)
			)
			(layer "F.Fab")
		)
		(fp_line
			(start -0.12065 0.2794)
			(end -0.12065 0.3048)
			(stroke
				(width 0.1)
				(type default)
			)
			(layer "F.Fab")
		)
		(fp_line
			(start -0.12065 0.3048)
			(end -0.67945 0.3048)
			(stroke
				(width 0.1)
				(type default)
			)
			(layer "F.Fab")
		)
		(fp_line
			(start 0.120396 0.2794)
			(end -0.12065 0.2794)
			(stroke
				(width 0.1)
				(type default)
			)
			(layer "F.Fab")
		)
		(fp_line
			(start 0.120396 0.3048)
			(end 0.120396 0.2794)
			(stroke
				(width 0.1)
				(type default)
			)
			(layer "F.Fab")
		)
		(fp_line
			(start 0.12065 -0.3048)
			(end 0.67945 -0.3048)
			(stroke
				(width 0.1)
				(type default)
			)
			(layer "F.Fab")
		)
		(fp_line
			(start 0.12065 -0.2794)
			(end 0.12065 -0.3048)
			(stroke
				(width 0.1)
				(type default)
			)
			(layer "F.Fab")
		)
		(fp_line
			(start 0.67945 -0.3048)
			(end 0.67945 0.3048)
			(stroke
				(width 0.1)
				(type default)
			)
			(layer "F.Fab")
		)
		(fp_line
			(start 0.67945 0.3048)
			(end 0.120396 0.3048)
			(stroke
				(width 0.1)
				(type default)
			)
			(layer "F.Fab")
		)
		(pad "1" smd circle
			(at -0.40005 0)
			(size 0 0)
			(layers "F.Cu" "F.Mask" "F.Paste")
			(net "P3V3_AUX")
		)
		(pad "2" smd circle
			(at 0.40005 0)
			(size 0 0)
			(layers "F.Cu" "F.Mask" "F.Paste")
			(net "GND")
		)
	)
	(footprint ""
		(layer "F.Cu")
		(at 194.08902 -29.12872 -90)
		(property "Reference" "R4708"
			(at 0 0 270)
			(layer "F.SilkS")
			(hide yes)
			(effects
				(font
					(size 1.27 1.27)
				)
			)
		)
		(property "Value" ""
			(at 0 0 270)
			(layer "F.Fab")
			(effects
				(font
					(size 1.27 1.27)
				)
			)
		)
		(duplicate_pad_numbers_are_jumpers no)
		(fp_line
			(start -0.7874 0.4064)
			(end -0.7874 -0.4064)
			(stroke
				(width 0.1524)
				(type default)
			)
			(layer "F.SilkS")
		)
		(fp_line
			(start 0.7874 0.4064)
			(end -0.7874 0.4064)
			(stroke
				(width 0.1524)
				(type default)
			)
			(layer "F.SilkS")
		)
		(fp_line
			(start -0.7874 -0.4064)
			(end 0.7874 -0.4064)
			(stroke
				(width 0.1524)
				(type default)
			)
			(layer "F.SilkS")
		)
		(fp_line
			(start 0.7874 -0.4064)
			(end 0.7874 0.4064)
			(stroke
				(width 0.1524)
				(type default)
			)
			(layer "F.SilkS")
		)
		(fp_line
			(start -0.67945 0.3048)
			(end -0.67945 -0.305054)
			(stroke
				(width 0.1)
				(type default)
			)
			(layer "F.Fab")
		)
		(fp_line
			(start -0.12065 0.3048)
			(end -0.67945 0.3048)
			(stroke
				(width 0.1)
				(type default)
			)
			(layer "F.Fab")
		)
		(fp_line
			(start 0.120396 0.3048)
			(end 0.120396 0.2794)
			(stroke
				(width 0.1)
				(type default)
			)
			(layer "F.Fab")
		)
		(fp_line
			(start 0.67945 0.3048)
			(end 0.120396 0.3048)
			(stroke
				(width 0.1)
				(type default)
			)
			(layer "F.Fab")
		)
		(fp_line
			(start -0.12065 0.2794)
			(end -0.12065 0.3048)
			(stroke
				(width 0.1)
				(type default)
			)
			(layer "F.Fab")
		)
		(fp_line
			(start 0.120396 0.2794)
			(end -0.12065 0.2794)
			(stroke
				(width 0.1)
				(type default)
			)
			(layer "F.Fab")
		)
		(fp_line
			(start -0.12065 -0.2794)
			(end 0.12065 -0.2794)
			(stroke
				(width 0.1)
				(type default)
			)
			(layer "F.Fab")
		)
		(fp_line
			(start 0.12065 -0.2794)
			(end 0.12065 -0.3048)
			(stroke
				(width 0.1)
				(type default)
			)
			(layer "F.Fab")
		)
		(fp_line
			(start 0.12065 -0.3048)
			(end 0.67945 -0.3048)
			(stroke
				(width 0.1)
				(type default)
			)
			(layer "F.Fab")
		)
		(fp_line
			(start 0.67945 -0.3048)
			(end 0.67945 0.3048)
			(stroke
				(width 0.1)
				(type default)
			)
			(layer "F.Fab")
		)
		(fp_line
			(start -0.67945 -0.305054)
			(end -0.12065 -0.305054)
			(stroke
				(width 0.1)
				(type default)
			)
			(layer "F.Fab")
		)
		(fp_line
			(start -0.12065 -0.305054)
			(end -0.12065 -0.2794)
			(stroke
				(width 0.1)
				(type default)
			)
			(layer "F.Fab")
		)
		(pad "1" smd circle
			(at -0.40005 0 270)
			(size 0 0)
			(layers "F.Cu" "F.Mask" "F.Paste")
			(net "P12V_SCM_FAULT_N")
		)
		(pad "2" smd circle
			(at 0.40005 0 270)
			(size 0 0)
			(layers "F.Cu" "F.Mask" "F.Paste")
			(net "P12V_SCM_FAULT_R_N")
		)
	)
	(footprint ""
		(layer "F.Cu")
		(at 253.97841 -44.849542 90)
		(property "Reference" "PR3970"
			(at 0 0 90)
			(layer "F.SilkS")
			(hide yes)
			(effects
				(font
					(size 1.27 1.27)
				)
			)
		)
		(property "Value" ""
			(at 0 0 90)
			(layer "F.Fab")
			(effects
				(font
					(size 1.27 1.27)
				)
			)
		)
		(duplicate_pad_numbers_are_jumpers no)
		(fp_line
			(start 0.7874 -0.4064)
			(end 0.7874 0.4064)
			(stroke
				(width 0.1524)
				(type default)
			)
			(layer "F.SilkS")
		)
		(fp_line
			(start -0.7874 -0.4064)
			(end 0.7874 -0.4064)
			(stroke
				(width 0.1524)
				(type default)
			)
			(layer "F.SilkS")
		)
		(fp_line
			(start 0.7874 0.4064)
			(end -0.7874 0.4064)
			(stroke
				(width 0.1524)
				(type default)
			)
			(layer "F.SilkS")
		)
		(fp_line
			(start -0.7874 0.4064)
			(end -0.7874 -0.4064)
			(stroke
				(width 0.1524)
				(type default)
			)
			(layer "F.SilkS")
		)
		(fp_line
			(start -0.12065 -0.305054)
			(end -0.12065 -0.2794)
			(stroke
				(width 0.1)
				(type default)
			)
			(layer "F.Fab")
		)
		(fp_line
			(start -0.67945 -0.305054)
			(end -0.12065 -0.305054)
			(stroke
				(width 0.1)
				(type default)
			)
			(layer "F.Fab")
		)
		(fp_line
			(start 0.67945 -0.3048)
			(end 0.67945 0.3048)
			(stroke
				(width 0.1)
				(type default)
			)
			(layer "F.Fab")
		)
		(fp_line
			(start 0.12065 -0.3048)
			(end 0.67945 -0.3048)
			(stroke
				(width 0.1)
				(type default)
			)
			(layer "F.Fab")
		)
		(fp_line
			(start 0.12065 -0.2794)
			(end 0.12065 -0.3048)
			(stroke
				(width 0.1)
				(type default)
			)
			(layer "F.Fab")
		)
		(fp_line
			(start -0.12065 -0.2794)
			(end 0.12065 -0.2794)
			(stroke
				(width 0.1)
				(type default)
			)
			(layer "F.Fab")
		)
		(fp_line
			(start 0.120396 0.2794)
			(end -0.12065 0.2794)
			(stroke
				(width 0.1)
				(type default)
			)
			(layer "F.Fab")
		)
		(fp_line
			(start -0.12065 0.2794)
			(end -0.12065 0.3048)
			(stroke
				(width 0.1)
				(type default)
			)
			(layer "F.Fab")
		)
		(fp_line
			(start 0.67945 0.3048)
			(end 0.120396 0.3048)
			(stroke
				(width 0.1)
				(type default)
			)
			(layer "F.Fab")
		)
		(fp_line
			(start 0.120396 0.3048)
			(end 0.120396 0.2794)
			(stroke
				(width 0.1)
				(type default)
			)
			(layer "F.Fab")
		)
		(fp_line
			(start -0.12065 0.3048)
			(end -0.67945 0.3048)
			(stroke
				(width 0.1)
				(type default)
			)
			(layer "F.Fab")
		)
		(fp_line
			(start -0.67945 0.3048)
			(end -0.67945 -0.305054)
			(stroke
				(width 0.1)
				(type default)
			)
			(layer "F.Fab")
		)
		(pad "1" smd circle
			(at -0.40005 0 90)
			(size 0 0)
			(layers "F.Cu" "F.Mask" "F.Paste")
			(net "P12V_E1S_SENSE_0")
		)
		(pad "2" smd circle
			(at 0.40005 0 90)
			(size 0 0)
			(layers "F.Cu" "F.Mask" "F.Paste")
			(net "GND")
		)
	)
)
